FILE_TYPE = CONNECTIVITY;
{Allegro Design Entry HDL 17.4-2019 S026 (4007227) 1/17/2022}
"PAGE_NUMBER" = 189;
0"NC";
END.
